(kicad_pcb
	(version 20260206)
	(generator "pcbnew")
	(generator_version "10.0")
	(general
		(thickness 1.6)
		(legacy_teardrops no)
	)
	(paper "A4")
	(title_block
		(title "Bryce Canyon_F.DPB_16315-1-OCP.brd")
		(comment 1 "Bryce Canyon / footprints 478-484 of 2223")
	)
	(layers
		(0 "F.Cu" signal "TOP")
		(4 "In1.Cu" signal "L2GND")
		(6 "In2.Cu" signal "L3")
		(8 "In3.Cu" signal "L4GND")
		(10 "In4.Cu" signal "L5")
		(12 "In5.Cu" signal "L6VCC")
		(14 "In6.Cu" signal "L7VCC")
		(16 "In7.Cu" signal "L8")
		(18 "In8.Cu" signal "L9GND")
		(20 "In9.Cu" signal "L10")
		(22 "In10.Cu" signal "L11GND")
		(2 "B.Cu" signal "BOTTOM")
		(9 "F.Adhes" user "F.Adhesive")
		(11 "B.Adhes" user "B.Adhesive")
		(13 "F.Paste" user "Package Geometry/Pastemask Top")
		(15 "B.Paste" user "Package Geometry/Pastemask Bottom")
		(5 "F.SilkS" user "Ref Des/Silkscreen Top")
		(7 "B.SilkS" user "Ref Des/Silkscreen Bottom")
		(1 "F.Mask" user "Board Geometry/Soldermask Top")
		(3 "B.Mask" user "Board Geometry/Soldermask Bottom")
		(17 "Dwgs.User" user "User.Drawings")
		(19 "Cmts.User" user "User.Comments")
		(21 "Eco1.User" user "User.Eco1")
		(23 "Eco2.User" user "User.Eco2")
		(25 "Edge.Cuts" user "Board Geometry/Outline")
		(27 "Margin" user)
		(31 "F.CrtYd" user "Package Geometry/Place Bound Top")
		(29 "B.CrtYd" user "Package Geometry/Place Bound Bottom")
		(35 "F.Fab" user "Ref Des/Assembly Top")
		(33 "B.Fab" user "Ref Des/Assembly Bottom")
	)
	(footprint ""
		(layer "F.Cu")
		(at 433.359052 -286.809942 -90)
		(property "Reference" "R352"
			(at 0 0 270)
			(layer "F.SilkS")
			(hide yes)
			(effects
				(font
					(size 1.27 1.27)
				)
			)
		)
		(property "Value" "300KR2F-GP"
			(at 0.064008 -3.993896 270)
			(unlocked yes)
			(layer "F.Fab")
			(hide yes)
			(effects
				(font
					(size 1.016 1.016)
					(thickness 0.1524)
				)
			)
		)
		(property "Device Type" "R402H16"
			(at 0.064008 -5.517896 270)
			(unlocked yes)
			(layer "F.Fab")
			(hide yes)
			(effects
				(font
					(size 1.016 1.016)
					(thickness 0.1524)
				)
			)
		)
		(duplicate_pad_numbers_are_jumpers no)
		(fp_line
			(start -0.508 -0.9398)
			(end -0.508 0.9398)
			(stroke
				(width 0.1524)
				(type default)
			)
			(layer "F.SilkS")
		)
		(fp_line
			(start 0.508 -0.9398)
			(end -0.508 -0.9398)
			(stroke
				(width 0.1524)
				(type default)
			)
			(layer "F.SilkS")
		)
		(fp_rect
			(start -0.508 0.9398)
			(end 0.508 -0.9398)
			(stroke
				(width 0)
				(type default)
			)
			(fill no)
			(layer "F.CrtYd")
		)
		(fp_rect
			(start -0.508 0.9398)
			(end 0.508 -0.9398)
			(stroke
				(width 0)
				(type default)
			)
			(fill no)
			(layer "F.Fab")
		)
		(pad "1" smd custom
			(at 0 -0.4445 270)
			(size 0.1397 0.1397)
			(layers "F.Cu" "F.Mask" "F.Paste")
			(net "SW_HDD_N9")
			(options
				(clearance outline)
				(anchor circle)
			)
			(primitives
				(gr_poly
					(pts
						(arc
							(start -0.1778 -0.2794)
							(mid -0.249642 -0.249642)
							(end -0.2794 -0.1778)
						)
						(arc
							(start -0.2794 0.1778)
							(mid -0.249642 0.249642)
							(end -0.1778 0.2794)
						)
						(arc
							(start 0.1778 0.2794)
							(mid 0.249642 0.249642)
							(end 0.2794 0.1778)
						)
						(arc
							(start 0.2794 -0.1778)
							(mid 0.249642 -0.249642)
							(end 0.1778 -0.2794)
						)
					)
					(width 0)
					(fill yes)
				)
			)
		)
		(pad "2" smd custom
			(at 0 0.4445 270)
			(size 0.1397 0.1397)
			(layers "F.Cu" "F.Mask" "F.Paste")
			(net "P12V_A")
			(options
				(clearance outline)
				(anchor circle)
			)
			(primitives
				(gr_poly
					(pts
						(arc
							(start -0.1778 -0.2794)
							(mid -0.249642 -0.249642)
							(end -0.2794 -0.1778)
						)
						(arc
							(start -0.2794 0.1778)
							(mid -0.249642 0.249642)
							(end -0.1778 0.2794)
						)
						(arc
							(start 0.1778 0.2794)
							(mid 0.249642 0.249642)
							(end 0.2794 0.1778)
						)
						(arc
							(start 0.2794 -0.1778)
							(mid 0.249642 -0.249642)
							(end 0.1778 -0.2794)
						)
					)
					(width 0)
					(fill yes)
				)
			)
		)
	)
	(footprint ""
		(layer "F.Cu")
		(at 234.963462 -261.71779 180)
		(property "Reference" "R37"
			(at 0 0 180)
			(layer "F.SilkS")
			(hide yes)
			(effects
				(font
					(size 1.27 1.27)
				)
			)
		)
		(property "Value" "4K7R2F-GP"
			(at 0.064008 -3.993896 180)
			(unlocked yes)
			(layer "F.Fab")
			(hide yes)
			(effects
				(font
					(size 1.016 1.016)
					(thickness 0.1524)
				)
			)
		)
		(property "Device Type" "R402H16"
			(at 0.064008 -5.517896 180)
			(unlocked yes)
			(layer "F.Fab")
			(hide yes)
			(effects
				(font
					(size 1.016 1.016)
					(thickness 0.1524)
				)
			)
		)
		(duplicate_pad_numbers_are_jumpers no)
		(fp_line
			(start 0.508 -0.9398)
			(end -0.508 -0.9398)
			(stroke
				(width 0.1524)
				(type default)
			)
			(layer "F.SilkS")
		)
		(fp_line
			(start -0.508 -0.9398)
			(end -0.508 0.9398)
			(stroke
				(width 0.1524)
				(type default)
			)
			(layer "F.SilkS")
		)
		(fp_rect
			(start -0.508 0.9398)
			(end 0.508 -0.9398)
			(stroke
				(width 0)
				(type default)
			)
			(fill no)
			(layer "F.CrtYd")
		)
		(fp_rect
			(start -0.508 0.9398)
			(end 0.508 -0.9398)
			(stroke
				(width 0)
				(type default)
			)
			(fill no)
			(layer "F.Fab")
		)
		(pad "1" smd custom
			(at 0 -0.4445 180)
			(size 0.1397 0.1397)
			(layers "F.Cu" "F.Mask" "F.Paste")
			(net "IO_EXP4_A1")
			(options
				(clearance outline)
				(anchor circle)
			)
			(primitives
				(gr_poly
					(pts
						(arc
							(start -0.1778 -0.2794)
							(mid -0.249642 -0.249642)
							(end -0.2794 -0.1778)
						)
						(arc
							(start -0.2794 0.1778)
							(mid -0.249642 0.249642)
							(end -0.1778 0.2794)
						)
						(arc
							(start 0.1778 0.2794)
							(mid 0.249642 0.249642)
							(end 0.2794 0.1778)
						)
						(arc
							(start 0.2794 -0.1778)
							(mid 0.249642 -0.249642)
							(end 0.1778 -0.2794)
						)
					)
					(width 0)
					(fill yes)
				)
			)
		)
		(pad "2" smd custom
			(at 0 0.4445 180)
			(size 0.1397 0.1397)
			(layers "F.Cu" "F.Mask" "F.Paste")
			(net "GND")
			(options
				(clearance outline)
				(anchor circle)
			)
			(primitives
				(gr_poly
					(pts
						(arc
							(start -0.1778 -0.2794)
							(mid -0.249642 -0.249642)
							(end -0.2794 -0.1778)
						)
						(arc
							(start -0.2794 0.1778)
							(mid -0.249642 0.249642)
							(end -0.1778 0.2794)
						)
						(arc
							(start 0.1778 0.2794)
							(mid 0.249642 0.249642)
							(end 0.2794 0.1778)
						)
						(arc
							(start 0.2794 -0.1778)
							(mid 0.249642 -0.249642)
							(end 0.1778 -0.2794)
						)
					)
					(width 0)
					(fill yes)
				)
			)
		)
	)
	(footprint ""
		(layer "F.Cu")
		(at 143.049498 -52.034694 90)
		(property "Reference" "R781"
			(at 0 0 90)
			(layer "F.SilkS")
			(hide yes)
			(effects
				(font
					(size 1.27 1.27)
				)
			)
		)
		(property "Value" "4K7R2J-2-GP"
			(at 0.064008 -3.993896 90)
			(unlocked yes)
			(layer "F.Fab")
			(hide yes)
			(effects
				(font
					(size 1.016 1.016)
					(thickness 0.1524)
				)
			)
		)
		(property "Device Type" "R402H16"
			(at 0.064008 -5.517896 90)
			(unlocked yes)
			(layer "F.Fab")
			(hide yes)
			(effects
				(font
					(size 1.016 1.016)
					(thickness 0.1524)
				)
			)
		)
		(duplicate_pad_numbers_are_jumpers no)
		(fp_line
			(start 0.508 -0.9398)
			(end -0.508 -0.9398)
			(stroke
				(width 0.1524)
				(type default)
			)
			(layer "F.SilkS")
		)
		(fp_line
			(start -0.508 -0.9398)
			(end -0.508 0.9398)
			(stroke
				(width 0.1524)
				(type default)
			)
			(layer "F.SilkS")
		)
		(fp_rect
			(start -0.508 0.9398)
			(end 0.508 -0.9398)
			(stroke
				(width 0)
				(type default)
			)
			(fill no)
			(layer "F.CrtYd")
		)
		(fp_rect
			(start -0.508 0.9398)
			(end 0.508 -0.9398)
			(stroke
				(width 0)
				(type default)
			)
			(fill no)
			(layer "F.Fab")
		)
		(pad "1" smd custom
			(at 0 -0.4445 90)
			(size 0.1397 0.1397)
			(layers "F.Cu" "F.Mask" "F.Paste")
			(net "P12V_A")
			(options
				(clearance outline)
				(anchor circle)
			)
			(primitives
				(gr_poly
					(pts
						(arc
							(start -0.1778 -0.2794)
							(mid -0.249642 -0.249642)
							(end -0.2794 -0.1778)
						)
						(arc
							(start -0.2794 0.1778)
							(mid -0.249642 0.249642)
							(end -0.1778 0.2794)
						)
						(arc
							(start 0.1778 0.2794)
							(mid 0.249642 0.249642)
							(end 0.2794 0.1778)
						)
						(arc
							(start 0.2794 -0.1778)
							(mid 0.249642 -0.249642)
							(end 0.1778 -0.2794)
						)
					)
					(width 0)
					(fill yes)
				)
			)
		)
		(pad "2" smd custom
			(at 0 0.4445 90)
			(size 0.1397 0.1397)
			(layers "F.Cu" "F.Mask" "F.Paste")
			(net "SW_HDD_P28")
			(options
				(clearance outline)
				(anchor circle)
			)
			(primitives
				(gr_poly
					(pts
						(arc
							(start -0.1778 -0.2794)
							(mid -0.249642 -0.249642)
							(end -0.2794 -0.1778)
						)
						(arc
							(start -0.2794 0.1778)
							(mid -0.249642 0.249642)
							(end -0.1778 0.2794)
						)
						(arc
							(start 0.1778 0.2794)
							(mid 0.249642 0.249642)
							(end 0.2794 0.1778)
						)
						(arc
							(start 0.2794 -0.1778)
							(mid 0.249642 -0.249642)
							(end 0.1778 -0.2794)
						)
					)
					(width 0)
					(fill yes)
				)
			)
		)
	)
	(footprint ""
		(layer "F.Cu")
		(at 95.608902 -162.749992 -90)
		(property "Reference" "VIA50"
			(at 0 0 270)
			(layer "F.SilkS")
			(hide yes)
			(effects
				(font
					(size 1.27 1.27)
				)
			)
		)
		(property "Value" "100OHM-8L-1D6MM-L18L16-GP"
			(at -3.7211 -4.5085 270)
			(unlocked yes)
			(layer "F.Fab")
			(hide yes)
			(effects
				(font
					(size 1.016 1.016)
					(thickness 0.1524)
				)
			)
		)
		(property "Device Type" "VIA-PCIE-4P-394076"
			(at -3.7211 -6.0325 270)
			(unlocked yes)
			(layer "F.Fab")
			(hide yes)
			(effects
				(font
					(size 1.016 1.016)
					(thickness 0.1524)
				)
			)
		)
		(duplicate_pad_numbers_are_jumpers no)
		(fp_rect
			(start -1.9685 0.381)
			(end 1.9685 -0.381)
			(stroke
				(width 0)
				(type default)
			)
			(fill no)
			(layer "F.CrtYd")
		)
		(fp_rect
			(start -1.9685 0.381)
			(end 1.9685 -0.381)
			(stroke
				(width 0)
				(type default)
			)
			(fill no)
			(layer "F.Fab")
		)
		(pad "1" thru_hole circle
			(at -1.5875 0 270)
			(size 0.508 0.508)
			(drill 0.254)
			(layers "*.Cu" "*.Mask")
			(remove_unused_layers no)
			(net "GND")
			(clearance 0.127)
			(thermal_gap 0.127)
		)
		(pad "2" thru_hole circle
			(at -0.5715 0 270)
			(size 0.508 0.508)
			(drill 0.254)
			(layers "*.Cu" "*.Mask")
			(remove_unused_layers no)
			(net "PHY_DRV_A_TO_SCC_A_14_DP")
			(clearance 0.127)
			(thermal_gap 0.127)
		)
		(pad "3" thru_hole circle
			(at 0.5715 0 270)
			(size 0.508 0.508)
			(drill 0.254)
			(layers "*.Cu" "*.Mask")
			(remove_unused_layers no)
			(net "PHY_DRV_A_TO_SCC_A_14_DN")
			(clearance 0.127)
			(thermal_gap 0.127)
		)
		(pad "4" thru_hole circle
			(at 1.5875 0 270)
			(size 0.508 0.508)
			(drill 0.254)
			(layers "*.Cu" "*.Mask")
			(remove_unused_layers no)
			(net "GND")
			(clearance 0.127)
			(thermal_gap 0.127)
		)
	)
	(footprint ""
		(layer "F.Cu")
		(at 426.755052 -45.252894 -90)
		(property "Reference" "Q199"
			(at 0 0 270)
			(layer "F.SilkS")
			(hide yes)
			(effects
				(font
					(size 1.27 1.27)
				)
			)
		)
		(property "Value" "2N7002KDW-GP"
			(at -2.3622 -8.2042 270)
			(unlocked yes)
			(layer "F.Fab")
			(hide yes)
			(effects
				(font
					(size 1.016 1.016)
					(thickness 0.1524)
				)
			)
		)
		(property "Device Type" "SOT-363H44"
			(at -2.3622 -10.1092 270)
			(unlocked yes)
			(layer "F.Fab")
			(hide yes)
			(effects
				(font
					(size 1.016 1.016)
					(thickness 0.1524)
				)
			)
		)
		(duplicate_pad_numbers_are_jumpers no)
		(fp_line
			(start -1.4478 1.7018)
			(end 1.4478 1.7018)
			(stroke
				(width 0.1524)
				(type default)
			)
			(layer "F.SilkS")
		)
		(fp_line
			(start 1.4478 1.7018)
			(end 1.4478 -1.7018)
			(stroke
				(width 0.1524)
				(type default)
			)
			(layer "F.SilkS")
		)
		(fp_line
			(start -1.27 1.524)
			(end -1.27 0.6604)
			(stroke
				(width 0.4826)
				(type default)
			)
			(layer "F.SilkS")
		)
		(fp_line
			(start -1.4478 -1.7018)
			(end -1.4478 1.7018)
			(stroke
				(width 0.1524)
				(type default)
			)
			(layer "F.SilkS")
		)
		(fp_line
			(start 1.4478 -1.7018)
			(end -1.4478 -1.7018)
			(stroke
				(width 0.1524)
				(type default)
			)
			(layer "F.SilkS")
		)
		(fp_poly
			(pts
				(xy -1.524 -1.778) (xy 1.524 -1.778) (xy 1.524 1.778) (xy -1.524 1.778)
			)
			(stroke
				(width 0)
				(type default)
			)
			(fill no)
			(layer "F.CrtYd")
		)
		(fp_poly
			(pts
				(xy -1.524 -1.778) (xy 1.524 -1.778) (xy 1.524 1.778) (xy -1.524 1.778)
			)
			(stroke
				(width 0)
				(type default)
			)
			(fill no)
			(layer "F.Fab")
		)
		(pad "1" smd rect
			(at -0.65024 0.9398 270)
			(size 0.4064 1.016)
			(layers "F.Cu" "F.Mask" "F.Paste")
			(net "GND")
		)
		(pad "2" smd rect
			(at 0 0.9398 270)
			(size 0.4064 1.016)
			(layers "F.Cu" "F.Mask" "F.Paste")
			(net "SW_PWR_R_HDD33")
		)
		(pad "3" smd rect
			(at 0.65024 0.9398 270)
			(size 0.4064 1.016)
			(layers "F.Cu" "F.Mask" "F.Paste")
			(net "SW_HDD_P33")
		)
		(pad "4" smd rect
			(at 0.65024 -0.9398 270)
			(size 0.4064 1.016)
			(layers "F.Cu" "F.Mask" "F.Paste")
			(net "GND")
		)
		(pad "5" smd rect
			(at 0 -0.9398 270)
			(size 0.4064 1.016)
			(layers "F.Cu" "F.Mask" "F.Paste")
			(net "SW_HDD_G33")
		)
		(pad "6" smd rect
			(at -0.65024 -0.9398 270)
			(size 0.4064 1.016)
			(layers "F.Cu" "F.Mask" "F.Paste")
			(net "SW_HDD_R33")
		)
	)
	(footprint ""
		(layer "F.Cu")
		(at 443.398402 -257.89255 -90)
		(property "Reference" "R1255"
			(at 0 0 270)
			(layer "F.SilkS")
			(hide yes)
			(effects
				(font
					(size 1.27 1.27)
				)
			)
		)
		(property "Value" "143KR2F-L-1-GP"
			(at 0.064008 -3.993896 270)
			(unlocked yes)
			(layer "F.Fab")
			(hide yes)
			(effects
				(font
					(size 1.016 1.016)
					(thickness 0.1524)
				)
			)
		)
		(property "Device Type" "R402H16"
			(at 0.064008 -5.517896 270)
			(unlocked yes)
			(layer "F.Fab")
			(hide yes)
			(effects
				(font
					(size 1.016 1.016)
					(thickness 0.1524)
				)
			)
		)
		(duplicate_pad_numbers_are_jumpers no)
		(fp_line
			(start -0.508 -0.9398)
			(end -0.508 0.9398)
			(stroke
				(width 0.1524)
				(type default)
			)
			(layer "F.SilkS")
		)
		(fp_line
			(start 0.508 -0.9398)
			(end -0.508 -0.9398)
			(stroke
				(width 0.1524)
				(type default)
			)
			(layer "F.SilkS")
		)
		(fp_rect
			(start -0.508 0.9398)
			(end 0.508 -0.9398)
			(stroke
				(width 0)
				(type default)
			)
			(fill no)
			(layer "F.CrtYd")
		)
		(fp_rect
			(start -0.508 0.9398)
			(end 0.508 -0.9398)
			(stroke
				(width 0)
				(type default)
			)
			(fill no)
			(layer "F.Fab")
		)
		(pad "1" smd custom
			(at 0 -0.4445 270)
			(size 0.1397 0.1397)
			(layers "F.Cu" "F.Mask" "F.Paste")
			(net "AGND_P5V_C")
			(options
				(clearance outline)
				(anchor circle)
			)
			(primitives
				(gr_poly
					(pts
						(arc
							(start -0.1778 -0.2794)
							(mid -0.249642 -0.249642)
							(end -0.2794 -0.1778)
						)
						(arc
							(start -0.2794 0.1778)
							(mid -0.249642 0.249642)
							(end -0.1778 0.2794)
						)
						(arc
							(start 0.1778 0.2794)
							(mid 0.249642 0.249642)
							(end 0.2794 0.1778)
						)
						(arc
							(start 0.2794 -0.1778)
							(mid 0.249642 -0.249642)
							(end 0.1778 -0.2794)
						)
					)
					(width 0)
					(fill yes)
				)
			)
		)
		(pad "2" smd custom
			(at 0 0.4445 270)
			(size 0.1397 0.1397)
			(layers "F.Cu" "F.Mask" "F.Paste")
			(net "P5V_C_TRIP")
			(options
				(clearance outline)
				(anchor circle)
			)
			(primitives
				(gr_poly
					(pts
						(arc
							(start -0.1778 -0.2794)
							(mid -0.249642 -0.249642)
							(end -0.2794 -0.1778)
						)
						(arc
							(start -0.2794 0.1778)
							(mid -0.249642 0.249642)
							(end -0.1778 0.2794)
						)
						(arc
							(start 0.1778 0.2794)
							(mid 0.249642 0.249642)
							(end 0.2794 0.1778)
						)
						(arc
							(start 0.2794 -0.1778)
							(mid 0.249642 -0.249642)
							(end 0.1778 -0.2794)
						)
					)
					(width 0)
					(fill yes)
				)
			)
		)
	)
	(footprint ""
		(layer "F.Cu")
		(at 35.797998 -176.127918 90)
		(property "Reference" "C198"
			(at 0 0 90)
			(layer "F.SilkS")
			(hide yes)
			(effects
				(font
					(size 1.27 1.27)
				)
			)
		)
		(property "Value" "SCD01U50V2KX-1GP"
			(at 1.1811 -2.7051 90)
			(unlocked yes)
			(layer "F.Fab")
			(hide yes)
			(effects
				(font
					(size 1.016 1.016)
					(thickness 0.1524)
				)
			)
		)
		(property "Device Type" "C402H22"
			(at 1.1811 -4.2291 90)
			(unlocked yes)
			(layer "F.Fab")
			(hide yes)
			(effects
				(font
					(size 1.016 1.016)
					(thickness 0.1524)
				)
			)
		)
		(duplicate_pad_numbers_are_jumpers no)
		(fp_rect
			(start -0.4318 0.9525)
			(end 0.4318 -0.9525)
			(stroke
				(width 0)
				(type default)
			)
			(fill no)
			(layer "F.CrtYd")
		)
		(fp_rect
			(start -0.4318 0.9525)
			(end 0.4318 -0.9525)
			(stroke
				(width 0)
				(type default)
			)
			(fill no)
			(layer "F.Fab")
		)
		(pad "1" smd custom
			(at 0 -0.4445 90)
			(size 0.1524 0.1524)
			(layers "F.Cu" "F.Mask" "F.Paste")
			(net "HDD_PRSNT_12")
			(options
				(clearance outline)
				(anchor circle)
			)
			(primitives
				(gr_poly
					(pts
						(arc
							(start 0.3048 -0.2032)
							(mid 0.275042 -0.275042)
							(end 0.2032 -0.3048)
						)
						(arc
							(start -0.2032 -0.3048)
							(mid -0.275042 -0.275042)
							(end -0.3048 -0.2032)
						)
						(arc
							(start -0.3048 0.2032)
							(mid -0.275042 0.275042)
							(end -0.2032 0.3048)
						)
						(arc
							(start 0.2032 0.3048)
							(mid 0.275042 0.275042)
							(end 0.3048 0.2032)
						)
					)
					(width 0)
					(fill yes)
				)
			)
		)
		(pad "2" smd custom
			(at 0 0.4445 90)
			(size 0.1524 0.1524)
			(layers "F.Cu" "F.Mask" "F.Paste")
			(net "GND")
			(options
				(clearance outline)
				(anchor circle)
			)
			(primitives
				(gr_poly
					(pts
						(arc
							(start 0.3048 -0.2032)
							(mid 0.275042 -0.275042)
							(end 0.2032 -0.3048)
						)
						(arc
							(start -0.2032 -0.3048)
							(mid -0.275042 -0.275042)
							(end -0.3048 -0.2032)
						)
						(arc
							(start -0.3048 0.2032)
							(mid -0.275042 0.275042)
							(end -0.2032 0.3048)
						)
						(arc
							(start 0.2032 0.3048)
							(mid 0.275042 0.275042)
							(end 0.3048 0.2032)
						)
					)
					(width 0)
					(fill yes)
				)
			)
		)
	)
)
